(kicad_pcb
	(version 20240108)
	(generator "pcbnew")
	(generator_version "8.0")
	(general
		(thickness 1.62)
		(legacy_teardrops no)
	)
	(paper "A4")
	(title_block
		(title "Jetson Orin Baseboard")
		(date "2025-03-12")
		(rev "1.3.4")
		(company "Antmicro Ltd")
		(comment 1 "www.antmicro.com")
		(comment 9 "footprints 520-523 of 677")
	)
	(layers
		(0 "F.Cu" signal)
		(1 "In1.Cu" signal)
		(2 "In2.Cu" signal)
		(3 "In3.Cu" signal)
		(4 "In4.Cu" jumper)
		(5 "In5.Cu" signal)
		(6 "In6.Cu" signal)
		(31 "B.Cu" signal)
		(32 "B.Adhes" user "B.Adhesive")
		(33 "F.Adhes" user "F.Adhesive")
		(34 "B.Paste" user)
		(35 "F.Paste" user)
		(36 "B.SilkS" user "B.Silkscreen")
		(37 "F.SilkS" user "F.Silkscreen")
		(38 "B.Mask" user)
		(39 "F.Mask" user)
		(40 "Dwgs.User" user "User.Drawings")
		(41 "Cmts.User" user "User.Comments")
		(42 "Eco1.User" user "User.Eco1")
		(43 "Eco2.User" user "User.Eco2")
		(44 "Edge.Cuts" user)
		(45 "Margin" user)
		(46 "B.CrtYd" user "B.Courtyard")
		(47 "F.CrtYd" user "F.Courtyard")
		(48 "B.Fab" user)
		(49 "F.Fab" user)
	)
	(footprint "antmicro-footprints:C_0402_1005Metric"
		(layer "B.Cu")
		(at 71.2 80.6 180)
		(descr "Capacitor SMD 0402")
		(tags "capacitor SMD 0402")
		(property "Reference" "C137"
			(at -0.94 -0.46 -90)
			(layer "B.SilkS")
			(effects
				(font
					(size 0.7 0.7)
					(thickness 0.15)
				)
				(justify left bottom mirror)
			)
		)
		(property "Value" "C_10u_0402"
			(at 0 -1.4 0)
			(layer "B.Fab")
			(effects
				(font
					(size 0.7 0.7)
					(thickness 0.15)
				)
				(justify left bottom mirror)
			)
		)
		(property "Footprint" "antmicro-footprints:C_0402_1005Metric"
			(at 0 0 180)
			(layer "F.Fab")
			(hide yes)
			(effects
				(font
					(size 1.27 1.27)
					(thickness 0.15)
				)
			)
		)
		(property "Datasheet" "https://www.yageo.com/en/Chart/Download/pdf/CC0402MRX5R5BB106"
			(at 0 0 180)
			(layer "F.Fab")
			(hide yes)
			(effects
				(font
					(size 1.27 1.27)
					(thickness 0.15)
				)
			)
		)
		(property "Author" "Antmicro"
			(at 142.4 161.2 0)
			(layer "B.Fab")
			(hide yes)
			(effects
				(font
					(size 1 1)
					(thickness 0.15)
				)
				(justify mirror)
			)
		)
		(property "Dielectric" ""
			(at 142.4 161.2 0)
			(layer "B.Fab")
			(hide yes)
			(effects
				(font
					(size 1 1)
					(thickness 0.15)
				)
				(justify mirror)
			)
		)
		(property "License" "Apache-2.0"
			(at 142.4 161.2 0)
			(layer "B.Fab")
			(hide yes)
			(effects
				(font
					(size 1 1)
					(thickness 0.15)
				)
				(justify mirror)
			)
		)
		(property "MPN" "CC0402MRX5R5BB106"
			(at 142.4 161.2 0)
			(layer "B.Fab")
			(hide yes)
			(effects
				(font
					(size 1 1)
					(thickness 0.15)
				)
				(justify mirror)
			)
		)
		(property "Manufacturer" "YAGEO"
			(at 142.4 161.2 0)
			(layer "B.Fab")
			(hide yes)
			(effects
				(font
					(size 1 1)
					(thickness 0.15)
				)
				(justify mirror)
			)
		)
		(property "Val" "10u"
			(at 142.4 161.2 0)
			(layer "B.Fab")
			(hide yes)
			(effects
				(font
					(size 1 1)
					(thickness 0.15)
				)
				(justify mirror)
			)
		)
		(property "Voltage" ""
			(at 142.4 161.2 0)
			(layer "B.Fab")
			(hide yes)
			(effects
				(font
					(size 1 1)
					(thickness 0.15)
				)
				(justify mirror)
			)
		)
		(sheetname "Supply")
		(sheetfile "supply.kicad_sch")
		(attr smd)
		(fp_rect
			(start -0.925 0.47)
			(end 0.925 -0.47)
			(stroke
				(width 0.05)
				(type default)
			)
			(fill none)
			(layer "B.CrtYd")
		)
		(fp_line
			(start 0.504 0.25)
			(end -0.494 0.25)
			(stroke
				(width 0.15)
				(type solid)
			)
			(layer "B.Fab")
		)
		(fp_line
			(start 0.504 -0.248)
			(end 0.504 0.25)
			(stroke
				(width 0.15)
				(type solid)
			)
			(layer "B.Fab")
		)
		(fp_line
			(start -0.494 0.25)
			(end -0.494 -0.248)
			(stroke
				(width 0.15)
				(type solid)
			)
			(layer "B.Fab")
		)
		(fp_line
			(start -0.494 -0.248)
			(end 0.504 -0.248)
			(stroke
				(width 0.15)
				(type solid)
			)
			(layer "B.Fab")
		)
		(fp_text user "License: Apache-2.0"
			(at -0.932 -5.17 0)
			(layer "B.Fab")
			(hide yes)
			(effects
				(font
					(size 0.7 0.7)
					(thickness 0.15)
				)
				(justify left bottom mirror)
			)
		)
		(fp_text user "${REFERENCE}"
			(at -0.932 -3.168 0)
			(layer "B.Fab")
			(hide yes)
			(effects
				(font
					(size 0.7 0.7)
					(thickness 0.15)
				)
				(justify left bottom mirror)
			)
		)
		(fp_text user "Author: Antmicro"
			(at -0.932 -4.17 0)
			(layer "B.Fab")
			(hide yes)
			(effects
				(font
					(size 0.7 0.7)
					(thickness 0.15)
				)
				(justify left bottom mirror)
			)
		)
		(pad "1" smd roundrect
			(at -0.48 0 180)
			(size 0.59 0.64)
			(layers "B.Cu" "B.Paste" "B.Mask")
			(roundrect_rratio 0.25)
			(net 1 "GND")
			(pintype "passive")
		)
		(pad "2" smd roundrect
			(at 0.48 0 180)
			(size 0.59 0.64)
			(layers "B.Cu" "B.Paste" "B.Mask")
			(roundrect_rratio 0.25)
			(net 138 "/Supply/3V3_LDO")
			(pintype "passive")
		)
	)
	(footprint "antmicro-footprints:C_0402_1005Metric"
		(layer "B.Cu")
		(at 95.55 90.975)
		(descr "Capacitor SMD 0402")
		(tags "capacitor SMD 0402")
		(property "Reference" "C132"
			(at 5.64 0.145 180)
			(layer "B.SilkS")
			(effects
				(font
					(size 0.7 0.7)
					(thickness 0.15)
				)
				(justify left bottom mirror)
			)
		)
		(property "Value" "C_100n_0402"
			(at 0 -1.4 180)
			(layer "B.Fab")
			(effects
				(font
					(size 0.7 0.7)
					(thickness 0.15)
				)
				(justify left bottom mirror)
			)
		)
		(property "Footprint" "antmicro-footprints:C_0402_1005Metric"
			(at 0 0 0)
			(layer "F.Fab")
			(hide yes)
			(effects
				(font
					(size 1.27 1.27)
					(thickness 0.15)
				)
			)
		)
		(property "Datasheet" "https://www.murata.com/products/productdetail?partno=GRM155R61H104KE14%23"
			(at 0 0 0)
			(layer "F.Fab")
			(hide yes)
			(effects
				(font
					(size 1.27 1.27)
					(thickness 0.15)
				)
			)
		)
		(property "Author" "Antmicro"
			(at 0 0 0)
			(layer "B.Fab")
			(hide yes)
			(effects
				(font
					(size 1 1)
					(thickness 0.15)
				)
				(justify mirror)
			)
		)
		(property "Dielectric" "X5R"
			(at 0 0 0)
			(layer "B.Fab")
			(hide yes)
			(effects
				(font
					(size 1 1)
					(thickness 0.15)
				)
				(justify mirror)
			)
		)
		(property "License" "Apache-2.0"
			(at 0 0 0)
			(layer "B.Fab")
			(hide yes)
			(effects
				(font
					(size 1 1)
					(thickness 0.15)
				)
				(justify mirror)
			)
		)
		(property "MPN" "GRM155R61H104KE14D"
			(at 0 0 0)
			(layer "B.Fab")
			(hide yes)
			(effects
				(font
					(size 1 1)
					(thickness 0.15)
				)
				(justify mirror)
			)
		)
		(property "Manufacturer" "Murata"
			(at 0 0 0)
			(layer "B.Fab")
			(hide yes)
			(effects
				(font
					(size 1 1)
					(thickness 0.15)
				)
				(justify mirror)
			)
		)
		(property "Val" "100n"
			(at 0 0 0)
			(layer "B.Fab")
			(hide yes)
			(effects
				(font
					(size 1 1)
					(thickness 0.15)
				)
				(justify mirror)
			)
		)
		(property "Voltage" "50V"
			(at 0 0 0)
			(layer "B.Fab")
			(hide yes)
			(effects
				(font
					(size 1 1)
					(thickness 0.15)
				)
				(justify mirror)
			)
		)
		(sheetname "HDMI")
		(sheetfile "hdmi.kicad_sch")
		(attr smd)
		(fp_rect
			(start -0.925 0.47)
			(end 0.925 -0.47)
			(stroke
				(width 0.05)
				(type default)
			)
			(fill none)
			(layer "B.CrtYd")
		)
		(fp_line
			(start -0.494 -0.248)
			(end 0.504 -0.248)
			(stroke
				(width 0.15)
				(type solid)
			)
			(layer "B.Fab")
		)
		(fp_line
			(start -0.494 0.25)
			(end -0.494 -0.248)
			(stroke
				(width 0.15)
				(type solid)
			)
			(layer "B.Fab")
		)
		(fp_line
			(start 0.504 -0.248)
			(end 0.504 0.25)
			(stroke
				(width 0.15)
				(type solid)
			)
			(layer "B.Fab")
		)
		(fp_line
			(start 0.504 0.25)
			(end -0.494 0.25)
			(stroke
				(width 0.15)
				(type solid)
			)
			(layer "B.Fab")
		)
		(fp_text user "Author: Antmicro"
			(at -0.932 -4.17 180)
			(layer "B.Fab")
			(hide yes)
			(effects
				(font
					(size 0.7 0.7)
					(thickness 0.15)
				)
				(justify left bottom mirror)
			)
		)
		(fp_text user "License: Apache-2.0"
			(at -0.932 -5.17 180)
			(layer "B.Fab")
			(hide yes)
			(effects
				(font
					(size 0.7 0.7)
					(thickness 0.15)
				)
				(justify left bottom mirror)
			)
		)
		(fp_text user "${REFERENCE}"
			(at -0.932 -3.168 180)
			(layer "B.Fab")
			(hide yes)
			(effects
				(font
					(size 0.7 0.7)
					(thickness 0.15)
				)
				(justify left bottom mirror)
			)
		)
		(pad "1" smd roundrect
			(at -0.48 0)
			(size 0.59 0.64)
			(layers "B.Cu" "B.Paste" "B.Mask")
			(roundrect_rratio 0.25)
			(net 666 "/HDMI/DP_MUX_D1+")
			(pintype "passive")
		)
		(pad "2" smd roundrect
			(at 0.48 0)
			(size 0.59 0.64)
			(layers "B.Cu" "B.Paste" "B.Mask")
			(roundrect_rratio 0.25)
			(net 419 "DP1_TXD2_HDMI_TX0_P")
			(pintype "passive")
		)
	)
	(footprint "antmicro-footprints:DFN3538"
		(layer "B.Cu")
		(at 48.04 105.7 180)
		(property "Reference" "D12"
			(at 0 2.8 0)
			(unlocked yes)
			(layer "B.SilkS")
			(effects
				(font
					(size 0.7 0.7)
					(thickness 0.15)
				)
				(justify left bottom mirror)
			)
		)
		(property "Value" "CD-MMBL110S"
			(at 0 -3.5 0)
			(unlocked yes)
			(layer "B.Fab")
			(effects
				(font
					(size 0.7 0.7)
					(thickness 0.15)
				)
				(justify left bottom mirror)
			)
		)
		(property "Footprint" "antmicro-footprints:DFN3538"
			(at 0 0 180)
			(layer "F.Fab")
			(hide yes)
			(effects
				(font
					(size 1.27 1.27)
					(thickness 0.15)
				)
			)
		)
		(property "Datasheet" "https://www.bourns.com/docs/product-datasheets/CD-MMBL110S.pdf"
			(at 0 0 180)
			(layer "F.Fab")
			(hide yes)
			(effects
				(font
					(size 1.27 1.27)
					(thickness 0.15)
				)
			)
		)
		(property "Author" "Antmicro"
			(at 96.08 211.4 0)
			(layer "B.Fab")
			(hide yes)
			(effects
				(font
					(size 1 1)
					(thickness 0.15)
				)
				(justify mirror)
			)
		)
		(property "License" "Apache-2.0"
			(at 96.08 211.4 0)
			(layer "B.Fab")
			(hide yes)
			(effects
				(font
					(size 1 1)
					(thickness 0.15)
				)
				(justify mirror)
			)
		)
		(property "MPN" "CD-MMBL110S"
			(at 96.08 211.4 0)
			(layer "B.Fab")
			(hide yes)
			(effects
				(font
					(size 1 1)
					(thickness 0.15)
				)
				(justify mirror)
			)
		)
		(property "Manufacturer" "Bourns"
			(at 96.08 211.4 0)
			(layer "B.Fab")
			(hide yes)
			(effects
				(font
					(size 1 1)
					(thickness 0.15)
				)
				(justify mirror)
			)
		)
		(sheetname "Ethernet")
		(sheetfile "ethernet.kicad_sch")
		(attr smd)
		(fp_line
			(start 1.8 2)
			(end 1.6 2)
			(stroke
				(width 0.15)
				(type solid)
			)
			(layer "B.SilkS")
		)
		(fp_line
			(start 1.8 -2.05)
			(end 1.8 2)
			(stroke
				(width 0.15)
				(type solid)
			)
			(layer "B.SilkS")
		)
		(fp_line
			(start 1.8 -2.05)
			(end 1.6 -2.05)
			(stroke
				(width 0.15)
				(type solid)
			)
			(layer "B.SilkS")
		)
		(fp_line
			(start 0.95 2)
			(end -0.95 2)
			(stroke
				(width 0.15)
				(type solid)
			)
			(layer "B.SilkS")
		)
		(fp_line
			(start 0.95 -2.05)
			(end -0.95 -2.05)
			(stroke
				(width 0.15)
				(type solid)
			)
			(layer "B.SilkS")
		)
		(fp_line
			(start 0.748 2.15)
			(end 0.748 2.452)
			(stroke
				(width 0.15)
				(type solid)
			)
			(layer "B.SilkS")
		)
		(fp_line
			(start 0.598 2.301)
			(end 0.9 2.301)
			(stroke
				(width 0.15)
				(type solid)
			)
			(layer "B.SilkS")
		)
		(fp_line
			(start -0.6 2.25)
			(end -0.902 2.25)
			(stroke
				(width 0.15)
				(type solid)
			)
			(layer "B.SilkS")
		)
		(fp_line
			(start -1.6 -2.05)
			(end -1.8 -2.05)
			(stroke
				(width 0.15)
				(type solid)
			)
			(layer "B.SilkS")
		)
		(fp_line
			(start -1.8 -2.05)
			(end -1.8 1.5)
			(stroke
				(width 0.15)
				(type solid)
			)
			(layer "B.SilkS")
		)
		(fp_rect
			(start -2.1 2.6)
			(end 2.1 -2.6)
			(stroke
				(width 0.05)
				(type solid)
			)
			(fill none)
			(layer "B.CrtYd")
		)
		(fp_line
			(start -1.801 1.25)
			(end -1.051 2)
			(stroke
				(width 0.15)
				(type solid)
			)
			(layer "B.Fab")
		)
		(fp_rect
			(start 1.8 -2.048)
			(end -1.8 2)
			(stroke
				(width 0.15)
				(type solid)
			)
			(fill none)
			(layer "B.Fab")
		)
		(fp_text user "~"
			(at -0.31 -2.8 0)
			(unlocked yes)
			(layer "B.SilkS")
			(effects
				(font
					(size 0.7 0.7)
					(thickness 0.15)
				)
				(justify left bottom mirror)
			)
		)
		(fp_text user "${REFERENCE}"
			(at -2.1 -4.599 0)
			(layer "B.Fab")
			(hide yes)
			(effects
				(font
					(size 0.7 0.7)
					(thickness 0.15)
				)
				(justify left bottom mirror)
			)
		)
		(fp_text user "License: Apache-2.0"
			(at -2.1 -6.599 0)
			(layer "B.Fab")
			(hide yes)
			(effects
				(font
					(size 0.7 0.7)
					(thickness 0.15)
				)
				(justify left bottom mirror)
			)
		)
		(fp_text user "Author: Antmicro"
			(at -2.1 -5.599 0)
			(layer "B.Fab")
			(hide yes)
			(effects
				(font
					(size 0.7 0.7)
					(thickness 0.15)
				)
				(justify left bottom mirror)
			)
		)
		(pad "1" smd roundrect
			(at -1.27 1.85 90)
			(size 1.4 0.48)
			(layers "B.Cu" "B.Paste" "B.Mask")
			(roundrect_rratio 0.25)
			(net 148 "Net-(D12-Pad1)")
			(pinfunction "1")
			(pintype "passive")
		)
		(pad "2" smd roundrect
			(at 1.27 1.85 90)
			(size 1.4 0.48)
			(layers "B.Cu" "B.Paste" "B.Mask")
			(roundrect_rratio 0.25)
			(net 149 "Net-(D12-Pad2)")
			(pinfunction "2")
			(pintype "passive")
		)
		(pad "3" smd roundrect
			(at -1.27 -1.85 90)
			(size 1.4 0.48)
			(layers "B.Cu" "B.Paste" "B.Mask")
			(roundrect_rratio 0.25)
			(net 121 "/Ethernet/PAIR_12")
			(pinfunction "3")
			(pintype "passive")
		)
		(pad "4" smd roundrect
			(at 1.27 -1.85 90)
			(size 1.4 0.48)
			(layers "B.Cu" "B.Paste" "B.Mask")
			(roundrect_rratio 0.25)
			(net 122 "/Ethernet/PAIR_36")
			(pinfunction "4")
			(pintype "passive")
		)
	)
	(footprint "antmicro-footprints:R_0402_1005Metric"
		(layer "B.Cu")
		(at 131.6 70.9 180)
		(descr "Resistor SMD 0402")
		(tags "resistor SMD 0402")
		(property "Reference" "R294"
			(at -1.4 0.4 0)
			(layer "B.SilkS")
			(effects
				(font
					(size 0.7 0.7)
					(thickness 0.15)
				)
				(justify left bottom mirror)
			)
		)
		(property "Value" "R_2k2_0402"
			(at 0 -1.4 0)
			(layer "B.Fab")
			(effects
				(font
					(size 0.7 0.7)
					(thickness 0.15)
				)
				(justify left bottom mirror)
			)
		)
		(property "Footprint" "antmicro-footprints:R_0402_1005Metric"
			(at 0 0 180)
			(layer "F.Fab")
			(hide yes)
			(effects
				(font
					(size 1.27 1.27)
					(thickness 0.15)
				)
			)
		)
		(property "Datasheet" "https://www.bourns.com/docs/product-datasheets/cr.pdf"
			(at 0 0 180)
			(layer "F.Fab")
			(hide yes)
			(effects
				(font
					(size 1.27 1.27)
					(thickness 0.15)
				)
			)
		)
		(property "Author" "Antmicro"
			(at 263.2 141.8 0)
			(layer "B.Fab")
			(hide yes)
			(effects
				(font
					(size 1 1)
					(thickness 0.15)
				)
				(justify mirror)
			)
		)
		(property "License" "Apache-2.0"
			(at 263.2 141.8 0)
			(layer "B.Fab")
			(hide yes)
			(effects
				(font
					(size 1 1)
					(thickness 0.15)
				)
				(justify mirror)
			)
		)
		(property "MPN" "CR0402-FX-2201GLF"
			(at 263.2 141.8 0)
			(layer "B.Fab")
			(hide yes)
			(effects
				(font
					(size 1 1)
					(thickness 0.15)
				)
				(justify mirror)
			)
		)
		(property "Manufacturer" "Bourns"
			(at 263.2 141.8 0)
			(layer "B.Fab")
			(hide yes)
			(effects
				(font
					(size 1 1)
					(thickness 0.15)
				)
				(justify mirror)
			)
		)
		(property "Tolerance" "1%"
			(at 263.2 141.8 0)
			(layer "B.Fab")
			(hide yes)
			(effects
				(font
					(size 1 1)
					(thickness 0.15)
				)
				(justify mirror)
			)
		)
		(property "Val" "2k2"
			(at 263.2 141.8 0)
			(layer "B.Fab")
			(hide yes)
			(effects
				(font
					(size 1 1)
					(thickness 0.15)
				)
				(justify mirror)
			)
		)
		(sheetname "SoM")
		(sheetfile "som.kicad_sch")
		(attr smd)
		(fp_rect
			(start -0.925 0.47)
			(end 0.925 -0.47)
			(stroke
				(width 0.05)
				(type default)
			)
			(fill none)
			(layer "B.CrtYd")
		)
		(fp_rect
			(start -0.5 0.25)
			(end 0.5 -0.25)
			(stroke
				(width 0.15)
				(type solid)
			)
			(fill none)
			(layer "B.Fab")
		)
		(fp_text user "Author: Antmicro"
			(at -0.95 -4.169 0)
			(layer "B.Fab")
			(hide yes)
			(effects
				(font
					(size 0.7 0.7)
					(thickness 0.15)
				)
				(justify left bottom mirror)
			)
		)
		(fp_text user "License: Apache-2.0"
			(at -0.95 -5.169 0)
			(layer "B.Fab")
			(hide yes)
			(effects
				(font
					(size 0.7 0.7)
					(thickness 0.15)
				)
				(justify left bottom mirror)
			)
		)
		(fp_text user "${REFERENCE}"
			(at -0.95 -3.168 0)
			(layer "B.Fab")
			(hide yes)
			(effects
				(font
					(size 0.7 0.7)
					(thickness 0.15)
				)
				(justify left bottom mirror)
			)
		)
		(pad "1" smd roundrect
			(at -0.48 0 180)
			(size 0.59 0.64)
			(layers "B.Cu" "B.Paste" "B.Mask")
			(roundrect_rratio 0.25)
			(net 732 "Net-(BT1-+)")
			(pintype "passive")
		)
		(pad "2" smd roundrect
			(at 0.48 0 180)
			(size 0.59 0.64)
			(layers "B.Cu" "B.Paste" "B.Mask")
			(roundrect_rratio 0.25)
			(net 85 "/SoM/PMIC_BBAT")
			(pintype "passive")
		)
	)
)
